FILE_TYPE = CONNECTIVITY;
{Allegro Design Entry HDL 17.2-2016 S081 (4005846) 1/11/2022}
"PAGE_NUMBER" = 182;
0"NC";
1"GND\g";
2"GND\g";
3"GND\g";
4"GND\g";
5"GND\g";
6"GND\g";
7"GND\g";
8"GND\g";
9"GND\g";
10"GND\g";
11"GND\g";
12"GND\g";
13"GND\g";
14"GND\g";
15"GND\g";
16"GND\g";
17"GND\g";
18"GND\g";
19"GND\g";
20"PVDD11_S3_P0\g";
21"PVDD18_S5_P0\g";
22"VSENSE_VSS_SENSE_C_P0";
23"VSENSE_PVDD11_S3_P0_DP";
24"NC_PVDD11_S3_P0_PWM7";
25"NC_PVDD11_S3_P0_IMON7";
26"PVDD11_S3_P0_VDDIO";
27"P3V3_STBY\g";
28"PVDD11_S3_P0_VCC";
29"PVDD11_S3_P0_VCCS";
30"NC_PVDD11_S3_P0_PWM3";
31"PVDD11_S3_P0_IMON1";
32"PVDD11_S3_P0_PWM1";
33"PVDD11_S3_P0_RESET_N";
34"PVDD18_S5_P0\g";
35"NC_PVDD11_S3_P0_PWM6";
36"NC_PVDD11_S3_P0_PWM4";
37"NC_PVDD11_S3_P0_IMON5";
38"NC_PVDD11_S3_P0_IMON4";
39"NC_PVDD11_S3_P0_IMON6";
40"NC_PVDD11_S3_P0_IMON8";
41"PVDD11_S3_P0_TEMP1";
42"PVDD11_S3_P0_TEMP0";
43"GND\g";
44"PWRGD_PVDD11_S3_P0_R";
45"GND\g";
46"GND\g";
47"PVDD11_S3_P0_PMSDA_R";
48"NC_PVDD11_S3_P0_SVTO";
49"PVDD11_S3_P0_PMSCL_R";
50"PVDD11_S3_P0_PMALERT_R";
51"PVDD11_S3_P0_EN_R";
52"PVDD11_S3_P0_PMALERT";
53"SMB_VR_3V3STBY_SDA";
54"SMB_VR_3V3STBY_SCL";
55"PWRGD_PVDD11_S3_P0";
56"PVDD11_S3_P0_EN";
57"P3V3_STBY\g";
58"VSENSE_PVDD11_S3_P0_R";
59"PVDD11_S3_P0_OCP_N_R";
60"GND\g";
61"GND\g";
62"NC_PVDD11_S3_P0_PG1";
63"PVDD11_S3_P0_ADDR_CFG";
64"PVDD11_S3_P0_VINSEN";
65"P12V_STBY\g";
66"PVDD11_S3_P0_OCP_N";
67"P3V3_STBY\g";
68"PVDD11_S3_P0_VMON";
69"P5V_STBY\g";
70"PVDD11_S3_P0_RESET_N_R";
71"NC_PVDD11_S3_P0_PWM8";
72"PVDD11_S3_P0_PWM2";
73"PVDD11_S3_P0_IMON2";
74"NC_PVDD11_S3_P0_IMON3";
75"NC_PVDD11_S3_P0_PWM5";
%"UNIVERSAL_GND"
"1","(-2925,5925)","0","pure_quanta_power","I10";
;
CDS_LIB"pure_quanta_power"
HDL_POWER"GND";
"A"1;
%"Q_CAP"
"1","(-5300,475)","0","pure_quanta","I100";
;
LOCATION"PC5"
SEC"1"
MATERIAL"X7R"
TOLERANCE"10%"
VALUE"0.1UF"
PART_NUMBER"CH4104K1B00"
VOLTAGE"25V"
PACK_TYPE"0402"
SEC_TYPE"0402"
CDS_LIB"pure_quanta";
"B"
$PN"2"2;
"A"
$PN"1"64;
%"Q_RES"
"1","(-5950,650)","0","pure_quanta","I101";
;
LOCATION"PR125"
$SEC"1"
CDS_SEC"1"
WATTAGE"1/16W"
MATERIAL"CHIP"
TOLERANCE"5%"
VALUE"0"
PART_NUMBER"CS00002JB38"
PACK_TYPE"0402LF"
CDS_LIB"pure_quanta";
"B"
$PN"2"64;
"A"
$PN"1"65;
%"UNIVERSAL_GND"
"1","(-5300,250)","0","pure_quanta_power","I102";
;
CDS_LIB"pure_quanta_power"
HDL_POWER"GND";
"A"2;
%"Q_RES"
"1","(-7200,825)","0","pure_quanta","I104";
;
LOCATION"PR113"
$SEC"1"
CDS_SEC"1"
WATTAGE"1/16W"
MATERIAL"CHIP"
TOLERANCE"1%"
VALUE"40.2K"
PART_NUMBER"TMP_QCS34022FB15"
PACK_TYPE"0402LF"
CDS_LIB"pure_quanta";
"B"
$PN"2"68;
"A"
$PN"1"69;
%"Q_RES"
"2","(-6450,650)","0","pure_quanta","I105";
;
LOCATION"PR3"
SEC"1"
WATTAGE"1/16W"
MATERIAL"CHIP"
TOLERANCE"1%"
VALUE"10K"
PART_NUMBER"TMP_QCS31002FB26"
PACK_TYPE"0402LF"
CDS_LIB"pure_quanta"
SEC_TYPE"0402LF";
"A"
$PN"1"68;
"B"
$PN"2"3;
%"UNIVERSAL_GND"
"1","(-6450,375)","0","pure_quanta_power","I107";
;
CDS_LIB"pure_quanta_power"
HDL_POWER"GND";
"A"3;
%"UNIVERSAL_GND"
"1","(-6875,400)","0","pure_quanta_power","I108";
;
CDS_LIB"pure_quanta_power"
HDL_POWER"GND";
"A"4;
%"VCC_CORE"
"1","(-7550,925)","0","pure_quanta_power","I109";
;
HDL_POWER"P5V_STBY"
CDS_LIB"pure_quanta_power";
"A"69;
%"Q_CAP"
"1","(-6875,650)","0","pure_quanta","I118";
;
LOCATION"PC193"
$SEC"1"
CDS_SEC"1"
MATERIAL"X7R"
TOLERANCE"10%"
VALUE"0.1UF"
PART_NUMBER"CH4104K1B00"
VOLTAGE"25V"
PACK_TYPE"0402"
CDS_LIB"pure_quanta";
"B"
$PN"2"4;
"A"
$PN"1"68;
%"UNIVERSAL_GND"
"1","(-2925,5425)","0","pure_quanta_power","I12";
;
CDS_LIB"pure_quanta_power"
HDL_POWER"GND";
"A"5;
%"Q_CAP"
"1","(-2925,5650)","0","pure_quanta","I13";
;
LOCATION"PC199"
$SEC"1"
CDS_SEC"1"
MATERIAL"X6S"
TOLERANCE"20%"
VALUE"10UF"
PART_NUMBER"CH6101MEB01"
VOLTAGE"6.3V"
PACK_TYPE"C0402"
CDS_LIB"pure_quanta";
"B"
$PN"2"5;
"A"
$PN"1"29;
%"VCC_CORE"
"1","(-2125,6375)","0","pure_quanta_power","I14";
;
HDL_POWER"P3V3_STBY"
CDS_LIB"pure_quanta_power";
"A"27;
%"UNIVERSAL_GND"
"1","(-5300,2550)","2","pure_quanta_power","I146";
;
CDS_LIB"pure_quanta_power"
HDL_POWER"GND";
"A"60;
%"Q_RES"
"1","(-2500,6275)","0","pure_quanta","I148";
;
LOCATION"PR130"
$SEC"1"
CDS_SEC"1"
WATTAGE"1/16W"
MATERIAL"CHIP"
TOLERANCE"1%"
VALUE"1"
PART_NUMBER"CS-1002FB23"
PACK_TYPE"0402LF"
CDS_LIB"pure_quanta";
"B"
$PN"2"27;
"A"
$PN"1"28;
%"VCC_CORE"
"1","(-6525,6500)","0","pure_quanta_power","I150";
;
HDL_POWER"P3V3_STBY"
CDS_LIB"pure_quanta_power";
"A"57;
%"Q_RES"
"1","(-6125,6375)","0","pure_quanta","I151";
;
LOCATION"PR117"
$SEC"1"
CDS_SEC"1"
WATTAGE"1/16W"
MATERIAL"CHIP"
TOLERANCE"1%"
VALUE"1K"
PART_NUMBER"TMP_QCS21002FB24"
PACK_TYPE"0402LF"
CDS_LIB"pure_quanta";
"B"
$PN"2"44;
"A"
$PN"1"57;
%"Q_RES"
"1","(-5900,6100)","0","pure_quanta","I152";
;
LOCATION"PR122"
$SEC"1"
CDS_SEC"1"
WATTAGE"1/16W"
MATERIAL"CHIP"
TOLERANCE"5%"
VALUE"0"
PART_NUMBER"CS00002JB38"
PACK_TYPE"0402LF"
CDS_LIB"pure_quanta";
"B"
$PN"2"44;
"A"
$PN"1"55;
%"Q_CAP"
"2","(-5250,6375)","0","pure_quanta","I153";
;
LOCATION"PC196"
$SEC"1"
CDS_SEC"1"
MATERIAL"EMPTY"
TOLERANCE"5%"
VALUE"1000PF"
PART_NUMBER"TMP_QCH21006JB10"
VOLTAGE"50V"
PACK_TYPE"0402"
CDS_LIB"pure_quanta";
"A"
$PN"1"44;
"B"
$PN"2"43;
%"UNIVERSAL_GND"
"1","(-5000,6300)","0","pure_quanta_power","I154";
;
CDS_LIB"pure_quanta_power"
HDL_POWER"GND";
"A"43;
%"UNIVERSAL_GND"
"1","(-3325,5425)","0","pure_quanta_power","I159";
;
CDS_LIB"pure_quanta_power"
HDL_POWER"GND";
"A"6;
%"Q_CAP"
"1","(-3325,5625)","0","pure_quanta","I160";
;
LOCATION"PC9"
$SEC"1"
CDS_SEC"1"
PART_NUMBER"CH4104K1B00"
MATERIAL"X7R"
TOLERANCE"10%"
VALUE"0.1UF"
VOLTAGE"25V"
PACK_TYPE"0402"
CDS_LIB"pure_quanta";
"B"
$PN"2"6;
"A"
$PN"1"29;
%"UNIVERSAL_GND"
"1","(-3325,5875)","0","pure_quanta_power","I161";
;
CDS_LIB"pure_quanta_power"
HDL_POWER"GND";
"A"7;
%"Q_CAP"
"1","(-3325,6125)","0","pure_quanta","I162";
;
LOCATION"PC4"
$SEC"1"
CDS_SEC"1"
MATERIAL"X7R"
TOLERANCE"10%"
VALUE"0.1UF"
PART_NUMBER"CH4104K1B00"
VOLTAGE"25V"
PACK_TYPE"0402"
CDS_LIB"pure_quanta";
"B"
$PN"2"7;
"A"
$PN"1"28;
%"Q_RES"
"1","(-3050,1200)","0","pure_quanta","I163";
;
LOCATION"PR412"
$SEC"1"
CDS_SEC"1"
WATTAGE"1/16W"
MATERIAL"CHIP"
TOLERANCE"5%"
VALUE"0"
PART_NUMBER"CS00002JB38"
PACK_TYPE"0402LF"
CDS_LIB"pure_quanta";
"B"
$PN"2"8;
"A"
$PN"1"41;
%"UNIVERSAL_GND"
"1","(-2600,1125)","0","pure_quanta_power","I165";
;
CDS_LIB"pure_quanta_power"
HDL_POWER"GND";
"A"8;
%"UNIVERSAL_GND"
"1","(-2075,1175)","0","pure_quanta_power","I167";
;
CDS_LIB"pure_quanta_power"
HDL_POWER"GND";
"A"9;
%"Q_RES"
"2","(-2075,1400)","0","pure_quanta","I168";
;
LOCATION"PR127"
$SEC"1"
CDS_SEC"1"
WATTAGE"1/16W"
MATERIAL"EMPTY"
TOLERANCE"5%"
VALUE"0"
PART_NUMBER"CS00002JB38"
PACK_TYPE"0402LF"
CDS_LIB"pure_quanta";
"A"
$PN"1"70;
"B"
$PN"2"9;
%"Q_RES"
"1","(-1600,1600)","0","pure_quanta","I178";
;
LOCATION"PR129"
$SEC"1"
CDS_SEC"1"
WATTAGE"1/16W"
MATERIAL"EMPTY"
TOLERANCE"5%"
VALUE"0"
PART_NUMBER"CS00002JB38"
PACK_TYPE"0402LF"
CDS_LIB"pure_quanta";
"B"
$PN"2"33;
"A"
$PN"1"70;
%"Q_RES"
"1","(-1650,1825)","0","pure_quanta","I179";
;
LOCATION"PR128"
$SEC"1"
CDS_SEC"1"
WATTAGE"1/16W"
MATERIAL"EMPTY"
TOLERANCE"1%"
VALUE"1K"
PART_NUMBER"TMP_QCS21002FB24"
PACK_TYPE"0402LF"
CDS_LIB"pure_quanta";
"B"
$PN"2"34;
"A"
$PN"1"70;
%"VCC_CORE"
"1","(-1300,1975)","0","pure_quanta_power","I180";
;
HDL_POWER"PVDD18_S5_P0"
CDS_LIB"pure_quanta_power";
"A"34;
%"UNIVERSAL_GND"
"1","(-5975,5100)","0","pure_quanta_power","I188";
;
CDS_LIB"pure_quanta_power"
HDL_POWER"GND";
"A"46;
%"Q_RES"
"1","(-6100,1700)","0","pure_quanta","I189";
;
LOCATION"PR458"
$SEC"1"
CDS_SEC"1"
WATTAGE"1/16W"
MATERIAL"EMPTY"
TOLERANCE"5%"
VALUE"0"
PART_NUMBER"CS00002JB38"
PACK_TYPE"0402LF"
CDS_LIB"pure_quanta";
"B"
$PN"2"26;
"A"
$PN"1"67;
%"VCC_CORE"
"1","(-6525,1825)","0","pure_quanta_power","I190";
;
HDL_POWER"P3V3_STBY"
CDS_LIB"pure_quanta_power";
"A"67;
%"Q_RES"
"1","(-3050,2300)","0","pure_quanta","I211";
;
LOCATION"PR419"
$SEC"1"
CDS_SEC"1"
WATTAGE"1/16W"
MATERIAL"CHIP"
TOLERANCE"5%"
VALUE"0"
PACK_TYPE"0402LF"
PART_NUMBER"CS00002JB38"
CDS_LIB"pure_quanta";
"B"
$PN"2"14;
"A"
$PN"1"25;
%"UNIVERSAL_GND"
"1","(-2600,4025)","0","pure_quanta_power","I212";
;
CDS_LIB"pure_quanta_power"
HDL_POWER"GND";
"A"10;
%"UNIVERSAL_GND"
"1","(-2600,3575)","0","pure_quanta_power","I213";
;
CDS_LIB"pure_quanta_power"
HDL_POWER"GND";
"A"11;
%"Q_RES"
"1","(-3025,4100)","0","pure_quanta","I214";
;
LOCATION"PR37"
$SEC"1"
CDS_SEC"1"
WATTAGE"1/16W"
MATERIAL"CHIP"
PART_NUMBER"CS00002JB38"
TOLERANCE"5%"
VALUE"0"
PACK_TYPE"0402LF"
CDS_LIB"pure_quanta";
"B"
$PN"2"10;
"A"
$PN"1"74;
%"Q_RES"
"1","(-3050,3650)","0","pure_quanta","I215";
;
LOCATION"PR33"
$SEC"1"
CDS_SEC"1"
WATTAGE"1/16W"
MATERIAL"CHIP"
TOLERANCE"5%"
VALUE"0"
PART_NUMBER"CS00002JB38"
PACK_TYPE"0402LF"
CDS_LIB"pure_quanta";
"B"
$PN"2"11;
"A"
$PN"1"38;
%"Q_RES"
"1","(-3050,3200)","0","pure_quanta","I216";
;
LOCATION"PR34"
$SEC"1"
CDS_SEC"1"
WATTAGE"1/16W"
MATERIAL"CHIP"
TOLERANCE"5%"
VALUE"0"
PART_NUMBER"CS00002JB38"
PACK_TYPE"0402LF"
CDS_LIB"pure_quanta";
"B"
$PN"2"12;
"A"
$PN"1"37;
%"UNIVERSAL_GND"
"1","(-2600,3125)","0","pure_quanta_power","I217";
;
CDS_LIB"pure_quanta_power"
HDL_POWER"GND";
"A"12;
%"UNIVERSAL_GND"
"1","(-2600,2675)","0","pure_quanta_power","I218";
;
CDS_LIB"pure_quanta_power"
HDL_POWER"GND";
"A"13;
%"UNIVERSAL_GND"
"1","(-2600,2225)","0","pure_quanta_power","I219";
;
CDS_LIB"pure_quanta_power"
HDL_POWER"GND";
"A"14;
%"UNIVERSAL_GND"
"1","(-2600,1775)","0","pure_quanta_power","I220";
;
CDS_LIB"pure_quanta_power"
HDL_POWER"GND";
"A"15;
%"Q_RES"
"1","(-3050,2750)","0","pure_quanta","I221";
;
LOCATION"PR35"
$SEC"1"
CDS_SEC"1"
PACK_TYPE"0402LF"
WATTAGE"1/16W"
MATERIAL"CHIP"
TOLERANCE"5%"
VALUE"0"
PART_NUMBER"CS00002JB38"
CDS_LIB"pure_quanta";
"B"
$PN"2"13;
"A"
$PN"1"39;
%"Q_RES"
"1","(-3050,1850)","0","pure_quanta","I222";
;
LOCATION"PR36"
$SEC"1"
CDS_SEC"1"
WATTAGE"1/16W"
MATERIAL"CHIP"
TOLERANCE"5%"
VALUE"0"
PART_NUMBER"CS00002JB38"
PACK_TYPE"0402LF"
CDS_LIB"pure_quanta";
"B"
$PN"2"15;
"A"
$PN"1"40;
%"Q_RES"
"2","(-5625,450)","0","pure_quanta","I227";
;
LOCATION"PR601"
$SEC"1"
CDS_SEC"1"
WATTAGE"1/16W"
MATERIAL"EMPTY"
TOLERANCE"1%"
VALUE"4.99K"
PART_NUMBER"CS24992FB07"
PACK_TYPE"0402LF"
CDS_LIB"pure_quanta";
"A"
$PN"1"64;
"B"
$PN"2"16;
%"UNIVERSAL_GND"
"1","(-5625,250)","0","pure_quanta_power","I228";
;
CDS_LIB"pure_quanta_power"
HDL_POWER"GND";
"A"16;
%"VCC_CORE"
"1","(-6175,725)","0","pure_quanta_power","I229";
;
HDL_POWER"P12V_STBY"
CDS_LIB"pure_quanta_power";
"A"65;
%"Q_RES"
"2","(-5600,1250)","0","pure_quanta","I3";
;
LOCATION"PR126"
$SEC"1"
CDS_SEC"1"
PACK_TYPE"0402LF"
WATTAGE"1/16W"
MATERIAL"CHIP"
TOLERANCE"1%"
VALUE"3.09K"
PART_NUMBER"CS23092FB00"
CDS_LIB"pure_quanta";
"A"
$PN"1"63;
"B"
$PN"2"18;
%"Q_CAP"
"1","(-3375,700)","0","pure_quanta","I36";
;
LOCATION"PC198"
$SEC"1"
CDS_SEC"1"
MATERIAL"X7R"
TOLERANCE"10%"
VALUE"470PF"
PART_NUMBER"TMP_QCH14706KB18"
VOLTAGE"50V"
PACK_TYPE"0402"
CDS_LIB"pure_quanta";
"B"
$PN"2"17;
"A"
$PN"1"42;
%"UNIVERSAL_GND"
"1","(-3375,425)","0","pure_quanta_power","I37";
;
CDS_LIB"pure_quanta_power"
HDL_POWER"GND";
"A"17;
%"Q_RES"
"1","(-5900,5950)","0","pure_quanta","I47";
;
LOCATION"PR123"
$SEC"1"
CDS_SEC"1"
WATTAGE"1/16W"
MATERIAL"CHIP"
TOLERANCE"5%"
VALUE"0"
PART_NUMBER"CS00002JB38"
PACK_TYPE"0402LF"
CDS_LIB"pure_quanta";
"B"
$PN"2"51;
"A"
$PN"1"56;
%"Q_CAP"
"2","(-5225,5825)","0","pure_quanta","I49";
;
LOCATION"PC197"
$SEC"1"
CDS_SEC"1"
MATERIAL"X7R"
TOLERANCE"5%"
VALUE"1000PF"
PART_NUMBER"TMP_QCH21006JB10"
VOLTAGE"50V"
PACK_TYPE"0402"
CDS_LIB"pure_quanta";
"A"
$PN"1"51;
"B"
$PN"2"45;
%"UNIVERSAL_GND"
"1","(-5600,1050)","0","pure_quanta_power","I5";
;
CDS_LIB"pure_quanta_power"
HDL_POWER"GND";
"A"18;
%"UNIVERSAL_GND"
"1","(-5000,5750)","0","pure_quanta_power","I50";
;
CDS_LIB"pure_quanta_power"
HDL_POWER"GND";
"A"45;
%"Q_RES"
"1","(-5975,4950)","0","pure_quanta","I66";
;
LOCATION"PR118"
$SEC"1"
CDS_SEC"1"
WATTAGE"1/16W"
MATERIAL"CHIP"
TOLERANCE"5%"
VALUE"0"
PART_NUMBER"CS00002JB38"
PACK_TYPE"0402LF"
CDS_LIB"pure_quanta";
"B"
$PN"2"49;
"A"
$PN"1"54;
%"Q_RES"
"1","(-5975,4800)","0","pure_quanta","I67";
;
LOCATION"PR119"
$SEC"1"
CDS_SEC"1"
WATTAGE"1/16W"
MATERIAL"CHIP"
TOLERANCE"5%"
VALUE"0"
PART_NUMBER"CS00002JB38"
PACK_TYPE"0402LF"
CDS_LIB"pure_quanta";
"B"
$PN"2"47;
"A"
$PN"1"53;
%"Q_RES"
"1","(-5975,4650)","0","pure_quanta","I68";
;
LOCATION"PR120"
$SEC"1"
CDS_SEC"1"
WATTAGE"1/16W"
MATERIAL"CHIP"
TOLERANCE"5%"
VALUE"0"
PART_NUMBER"CS00002JB38"
PACK_TYPE"0402LF"
CDS_LIB"pure_quanta";
"B"
$PN"2"50;
"A"
$PN"1"52;
%"RAA229621GNPHA0"
"1","(-4325,3350)","0","pure_quanta","I7";
;
LOCATION"PU21"
$SEC"1"
CDS_SEC"1"
PART_NUMBER"AR0T6GPV006"
VALUE"RAA229621GNP#HA0"
MATERIAL"IC"
PART_TYPE"SMLF"
CDS_LIB"pure_quanta"
NEEDS_NO_SIZE"TRUE"
CDS_LMAN_SYM_OUTLINE"-550,2850,500,-2850";
"CS0"
$PN"30"40;
"PWM0"
$PN"1"71;
"TEMP1"
$PN"35"41;
"EN1||ADDR_CFG"
$PN"34"63;
"TH_GND"
$PN"TH"61;
"OCP_L \B"
$PN"33"59;
"CS2"
$PN"28"39;
"PWM2"
$PN"3"35;
"CS3"
$PN"27"37;
"PWM3"
$PN"4"75;
"PWM7"
$PN"8"32;
"CS1"
$PN"29"25;
"RGND1"
$PN"31"60;
"VSEN1"
$PN"32"60;
"VDDIO"
$PN"15"26;
"TEMP0"
$PN"36"42;
"VINSEN"
$PN"38"64;
"VMON||IINSEN"
$PN"37"68;
"VCCS"
$PN"40"29;
"PWM6"
$PN"7"72;
"PG0"
$PN"12"44;
"PWM1"
$PN"2"24;
"VSEN0"
$PN"21"58;
"PWM5"
$PN"6"30;
"PWM4"
$PN"5"36;
"PMSDA"
$PN"9"47;
"RGND0"
$PN"22"22;
"EN0"
$PN"13"51;
"NPMALERT \B"
$PN"11"50;
"SVD"
$PN"17"46;
"PG1"
$PN"16"62;
"CS4"
$PN"26"38;
"CS5"
$PN"25"74;
"RESET_L \B"
$PN"14"70;
"SVTO"
$PN"19"48;
"CS6"
$PN"24"73;
"SVC"
$PN"18"46;
"PMSCL"
$PN"10"49;
"SVTI"
$PN"20"46;
"VCC"
$PN"39"28;
"CS7"
$PN"23"31;
%"Q_CAP"
"1","(-5675,3925)","0","pure_quanta","I76";
;
LOCATION"PC194"
$SEC"1"
CDS_SEC"1"
MATERIAL"X7R"
TOLERANCE"10%"
VALUE"3300PF"
PART_NUMBER"TMP_QCH2336K1B12"
VOLTAGE"50V"
PACK_TYPE"0402"
CDS_LIB"pure_quanta";
"B"
$PN"2"22;
"A"
$PN"1"58;
%"Q_RES"
"1","(-5975,4050)","0","pure_quanta","I77";
;
LOCATION"PR121"
$SEC"1"
CDS_SEC"1"
WATTAGE"1/16W"
MATERIAL"CHIP"
TOLERANCE"1%"
VALUE"10"
PART_NUMBER"TMP_QCS01002FB21"
PACK_TYPE"0402LF"
CDS_LIB"pure_quanta";
"B"
$PN"2"58;
"A"
$PN"1"23;
%"Q_CAP"
"1","(-2925,6125)","0","pure_quanta","I8";
;
LOCATION"PC200"
$SEC"1"
CDS_SEC"1"
MATERIAL"X6S"
TOLERANCE"10%"
VALUE"1UF"
PART_NUMBER"CH5103KEB01"
VOLTAGE"16V"
PACK_TYPE"C0402"
CDS_LIB"pure_quanta";
"B"
$PN"2"1;
"A"
$PN"1"28;
%"Q_RES"
"2","(-6800,4225)","0","pure_quanta","I81";
;
LOCATION"PR114"
$SEC"1"
CDS_SEC"1"
WATTAGE"1/16W"
MATERIAL"CHIP"
PART_NUMBER"CS04992FB31"
PACK_TYPE"0402LF"
VALUE"49.9"
TOLERANCE"1%"
CDS_LIB"pure_quanta";
"A"
$PN"1"20;
"B"
$PN"2"23;
%"Q_RES"
"2","(-6800,3650)","0","pure_quanta","I82";
;
LOCATION"PR115"
$SEC"1"
CDS_SEC"1"
WATTAGE"1/16W"
MATERIAL"CHIP"
PART_NUMBER"CS04992FB31"
PACK_TYPE"0402LF"
VALUE"49.9"
TOLERANCE"1%"
CDS_LIB"pure_quanta";
"A"
$PN"1"22;
"B"
$PN"2"19;
%"UNIVERSAL_GND"
"1","(-6800,3475)","0","pure_quanta_power","I83";
;
CDS_LIB"pure_quanta_power"
HDL_POWER"GND";
"A"19;
%"VCC_CORE"
"1","(-6800,4425)","0","pure_quanta_power","I84";
;
HDL_POWER"PVDD11_S3_P0"
CDS_LIB"pure_quanta_power";
"A"20;
%"Q_RES"
"1","(-6175,2100)","0","pure_quanta","I94";
;
LOCATION"PR116"
$SEC"1"
CDS_SEC"1"
WATTAGE"1/16W"
MATERIAL"EMPTY"
TOLERANCE"5%"
VALUE"0"
PART_NUMBER"CS00002JB38"
PACK_TYPE"0402LF"
CDS_LIB"pure_quanta";
"B"
$PN"2"59;
"A"
$PN"1"66;
%"Q_RES"
"2","(-5900,2325)","0","pure_quanta","I95";
;
LOCATION"PR124"
$SEC"1"
CDS_SEC"1"
WATTAGE"1/16W"
MATERIAL"EMPTY"
TOLERANCE"1%"
VALUE"1K"
PART_NUMBER"TMP_QCS21002FB24"
PACK_TYPE"0402LF"
CDS_LIB"pure_quanta";
"A"
$PN"1"21;
"B"
$PN"2"59;
%"VCC_CORE"
"1","(-5900,2525)","0","pure_quanta_power","I96";
;
HDL_POWER"PVDD18_S5_P0"
CDS_LIB"pure_quanta_power";
"A"21;
%"UNIVERSAL_GND"
"1","(-5100,450)","0","pure_quanta_power","I99";
;
CDS_LIB"pure_quanta_power"
HDL_POWER"GND";
"A"61;
END.
